(kicad_pcb
	(version 20260206)
	(generator "pcbnew")
	(generator_version "10.0")
	(general
		(thickness 1.6)
		(legacy_teardrops no)
	)
	(paper "A4")
	(title_block
		(title "v1-chassis-manager — T6M_CM_d_v01_1031_1645.brd")
		(comment 1 "Open CloudServer (Microsoft) / footprints 2453-2462 of 2512")
	)
	(layers
		(0 "F.Cu" signal "TOP")
		(4 "In1.Cu" signal "GND1")
		(6 "In2.Cu" signal "IN1")
		(8 "In3.Cu" signal "VCC1")
		(10 "In4.Cu" signal "VCC2")
		(12 "In5.Cu" signal "GND2")
		(14 "In6.Cu" signal "IN2")
		(16 "In7.Cu" signal "IN3")
		(18 "In8.Cu" signal "GND3")
		(2 "B.Cu" signal "BOTTOM")
		(9 "F.Adhes" user "F.Adhesive")
		(11 "B.Adhes" user "B.Adhesive")
		(13 "F.Paste" user "Package Geometry/Pastemask Top")
		(15 "B.Paste" user "Package Geometry/Pastemask Bottom")
		(5 "F.SilkS" user "Ref Des/Silkscreen Top")
		(7 "B.SilkS" user "Ref Des/Silkscreen Bottom")
		(1 "F.Mask" user "Board Geometry/Soldermask Top")
		(3 "B.Mask" user "Board Geometry/Soldermask Bottom")
		(17 "Dwgs.User" user "User.Drawings")
		(19 "Cmts.User" user "User.Comments")
		(21 "Eco1.User" user "User.Eco1")
		(23 "Eco2.User" user "User.Eco2")
		(25 "Edge.Cuts" user "Board Geometry/Outline")
		(27 "Margin" user)
		(31 "F.CrtYd" user "Package Geometry/Place Bound Top")
		(29 "B.CrtYd" user "Package Geometry/Place Bound Bottom")
		(35 "F.Fab" user "Ref Des/Assembly Top")
		(33 "B.Fab" user "Ref Des/Assembly Bottom")
	)
	(footprint ""
		(layer "B.Cu")
		(at 91.102434 -187.842398)
		(property "Reference" "C675"
			(at -2.352294 -3.283966 0)
			(unlocked yes)
			(layer "B.SilkS")
			(effects
				(font
					(size 0.7874 0.5842)
					(thickness 0.1524)
				)
				(justify left mirror)
			)
		)
		(property "Value" ""
			(at 0 0 0)
			(layer "B.Fab")
			(effects
				(font
					(size 1.27 1.27)
				)
				(justify mirror)
			)
		)
		(duplicate_pad_numbers_are_jumpers no)
		(fp_line
			(start -0.7874 -0.4064)
			(end -0.7874 0.4064)
			(stroke
				(width 0.1524)
				(type default)
			)
			(layer "B.SilkS")
		)
		(fp_line
			(start -0.7874 0.4064)
			(end 0.7874 0.4064)
			(stroke
				(width 0.1524)
				(type default)
			)
			(layer "B.SilkS")
		)
		(fp_line
			(start 0 0.381)
			(end 0 -0.381)
			(stroke
				(width 0.1524)
				(type default)
			)
			(layer "B.SilkS")
		)
		(fp_line
			(start 0.7874 -0.4064)
			(end -0.7874 -0.4064)
			(stroke
				(width 0.1524)
				(type default)
			)
			(layer "B.SilkS")
		)
		(fp_line
			(start 0.7874 0.4064)
			(end 0.7874 -0.4064)
			(stroke
				(width 0.1524)
				(type default)
			)
			(layer "B.SilkS")
		)
		(fp_poly
			(pts
				(xy 0.5334 0.254) (xy 0.635 0.254) (xy 0.635 0.2286) (xy 0.635 -0.254) (xy 0.5334 -0.254) (xy 0.5334 -0.2794)
				(xy -0.5334 -0.2794) (xy -0.5334 -0.254) (xy -0.635 -0.254) (xy -0.635 0.254) (xy -0.5334 0.254)
				(xy -0.5334 0.2794) (xy 0.508 0.2794) (xy 0.5334 0.2794)
			)
			(stroke
				(width 0)
				(type default)
			)
			(fill no)
			(layer "B.CrtYd")
		)
		(pad "1" smd rect
			(at -0.40005 0 180)
			(size 0.4572 0.508)
			(layers "B.Cu" "B.Mask" "B.Paste")
			(net "UART_T5_NODE1_TXD_R")
		)
		(pad "2" smd rect
			(at 0.40005 0 180)
			(size 0.4572 0.508)
			(layers "B.Cu" "B.Mask" "B.Paste")
			(net "GND")
		)
	)
	(footprint ""
		(layer "B.Cu")
		(at 137.668508 -46.952154 90)
		(property "Reference" "R1132"
			(at 3.212846 11.910822 270)
			(unlocked yes)
			(layer "B.SilkS")
			(effects
				(font
					(size 0.7874 0.5842)
					(thickness 0.1524)
				)
				(justify left mirror)
			)
		)
		(property "Value" ""
			(at 0 0 90)
			(layer "B.Fab")
			(effects
				(font
					(size 1.27 1.27)
				)
				(justify mirror)
			)
		)
		(duplicate_pad_numbers_are_jumpers no)
		(fp_line
			(start 0.7874 -0.4064)
			(end -0.7874 -0.4064)
			(stroke
				(width 0.1524)
				(type default)
			)
			(layer "B.SilkS")
		)
		(fp_line
			(start -0.7874 -0.4064)
			(end -0.7874 0.4064)
			(stroke
				(width 0.1524)
				(type default)
			)
			(layer "B.SilkS")
		)
		(fp_line
			(start 0.7874 0.4064)
			(end 0.7874 -0.4064)
			(stroke
				(width 0.1524)
				(type default)
			)
			(layer "B.SilkS")
		)
		(fp_line
			(start -0.7874 0.4064)
			(end 0.7874 0.4064)
			(stroke
				(width 0.1524)
				(type default)
			)
			(layer "B.SilkS")
		)
		(fp_poly
			(pts
				(xy 0.508 0.2794) (xy 0.508 0.2286) (xy 0.635 0.2286) (xy 0.635 -0.254) (xy 0.5334 -0.254) (xy 0.5334 -0.2794)
				(xy -0.5334 -0.2794) (xy -0.5334 -0.254) (xy -0.635 -0.254) (xy -0.635 0.254) (xy -0.5334 0.254)
				(xy -0.5334 0.2794)
			)
			(stroke
				(width 0)
				(type default)
			)
			(fill no)
			(layer "B.CrtYd")
		)
		(pad "1" smd rect
			(at -0.40005 0 270)
			(size 0.4572 0.508)
			(layers "B.Cu" "B.Mask" "B.Paste")
			(net "P5V_NODE1")
		)
		(pad "2" smd rect
			(at 0.40005 0 270)
			(size 0.4572 0.508)
			(layers "B.Cu" "B.Mask" "B.Paste")
			(net "UART_DTR_P3_R_N")
		)
	)
	(footprint ""
		(layer "B.Cu")
		(at 104.408224 -69.273674)
		(property "Reference" "R226"
			(at -4.704334 2.793746 0)
			(unlocked yes)
			(layer "B.SilkS")
			(effects
				(font
					(size 0.7874 0.5842)
					(thickness 0.1524)
				)
				(justify left mirror)
			)
		)
		(property "Value" ""
			(at 0 0 0)
			(layer "B.Fab")
			(effects
				(font
					(size 1.27 1.27)
				)
				(justify mirror)
			)
		)
		(duplicate_pad_numbers_are_jumpers no)
		(fp_line
			(start -0.7874 -0.4064)
			(end -0.7874 0.4064)
			(stroke
				(width 0.1524)
				(type default)
			)
			(layer "B.SilkS")
		)
		(fp_line
			(start -0.7874 0.4064)
			(end 0.7874 0.4064)
			(stroke
				(width 0.1524)
				(type default)
			)
			(layer "B.SilkS")
		)
		(fp_line
			(start 0.7874 -0.4064)
			(end -0.7874 -0.4064)
			(stroke
				(width 0.1524)
				(type default)
			)
			(layer "B.SilkS")
		)
		(fp_line
			(start 0.7874 0.4064)
			(end 0.7874 -0.4064)
			(stroke
				(width 0.1524)
				(type default)
			)
			(layer "B.SilkS")
		)
		(fp_poly
			(pts
				(xy 0.508 0.2794) (xy 0.508 0.2286) (xy 0.635 0.2286) (xy 0.635 -0.254) (xy 0.5334 -0.254) (xy 0.5334 -0.2794)
				(xy -0.5334 -0.2794) (xy -0.5334 -0.254) (xy -0.635 -0.254) (xy -0.635 0.254) (xy -0.5334 0.254)
				(xy -0.5334 0.2794)
			)
			(stroke
				(width 0)
				(type default)
			)
			(fill no)
			(layer "B.CrtYd")
		)
		(pad "1" smd rect
			(at -0.40005 0 180)
			(size 0.4572 0.508)
			(layers "B.Cu" "B.Mask" "B.Paste")
			(net "P3V3_STB_NODE1")
		)
		(pad "2" smd rect
			(at 0.40005 0 180)
			(size 0.4572 0.508)
			(layers "B.Cu" "B.Mask" "B.Paste")
			(net "XDP_CPU_NODE1_PWROK_STALL_L")
		)
	)
	(footprint ""
		(layer "B.Cu")
		(at 61.34735 -71.022718 -90)
		(property "Reference" "C107"
			(at 33.04921 14.61262 270)
			(unlocked yes)
			(layer "B.SilkS")
			(effects
				(font
					(size 0.7874 0.5842)
					(thickness 0.1524)
				)
				(justify left mirror)
			)
		)
		(property "Value" ""
			(at 0 0 90)
			(layer "B.Fab")
			(effects
				(font
					(size 1.27 1.27)
				)
				(justify mirror)
			)
		)
		(duplicate_pad_numbers_are_jumpers no)
		(fp_line
			(start -0.7874 0.4064)
			(end 0.7874 0.4064)
			(stroke
				(width 0.1524)
				(type default)
			)
			(layer "B.SilkS")
		)
		(fp_line
			(start 0.7874 0.4064)
			(end 0.7874 -0.4064)
			(stroke
				(width 0.1524)
				(type default)
			)
			(layer "B.SilkS")
		)
		(fp_line
			(start 0 0.381)
			(end 0 -0.381)
			(stroke
				(width 0.1524)
				(type default)
			)
			(layer "B.SilkS")
		)
		(fp_line
			(start -0.7874 -0.4064)
			(end -0.7874 0.4064)
			(stroke
				(width 0.1524)
				(type default)
			)
			(layer "B.SilkS")
		)
		(fp_line
			(start 0.7874 -0.4064)
			(end -0.7874 -0.4064)
			(stroke
				(width 0.1524)
				(type default)
			)
			(layer "B.SilkS")
		)
		(fp_poly
			(pts
				(xy 0.5334 0.254) (xy 0.635 0.254) (xy 0.635 0.2286) (xy 0.635 -0.254) (xy 0.5334 -0.254) (xy 0.5334 -0.2794)
				(xy -0.5334 -0.2794) (xy -0.5334 -0.254) (xy -0.635 -0.254) (xy -0.635 0.254) (xy -0.5334 0.254)
				(xy -0.5334 0.2794) (xy 0.508 0.2794) (xy 0.5334 0.2794)
			)
			(stroke
				(width 0)
				(type default)
			)
			(fill no)
			(layer "B.CrtYd")
		)
		(pad "1" smd rect
			(at -0.40005 0 90)
			(size 0.4572 0.508)
			(layers "B.Cu" "B.Mask" "B.Paste")
			(net "P1V05_NODE1")
		)
		(pad "2" smd rect
			(at 0.40005 0 90)
			(size 0.4572 0.508)
			(layers "B.Cu" "B.Mask" "B.Paste")
			(net "GND")
		)
	)
	(footprint ""
		(layer "B.Cu")
		(at 70.966584 -88.83142 180)
		(property "Reference" "R87"
			(at -3.025648 -0.075184 0)
			(unlocked yes)
			(layer "B.SilkS")
			(effects
				(font
					(size 0.7874 0.5842)
					(thickness 0.1524)
				)
				(justify left mirror)
			)
		)
		(property "Value" ""
			(at 0 0 0)
			(layer "B.Fab")
			(effects
				(font
					(size 1.27 1.27)
				)
				(justify mirror)
			)
		)
		(duplicate_pad_numbers_are_jumpers no)
		(fp_line
			(start 0.7874 0.4064)
			(end 0.7874 -0.4064)
			(stroke
				(width 0.1524)
				(type default)
			)
			(layer "B.SilkS")
		)
		(fp_line
			(start 0.7874 -0.4064)
			(end -0.7874 -0.4064)
			(stroke
				(width 0.1524)
				(type default)
			)
			(layer "B.SilkS")
		)
		(fp_line
			(start -0.7874 0.4064)
			(end 0.7874 0.4064)
			(stroke
				(width 0.1524)
				(type default)
			)
			(layer "B.SilkS")
		)
		(fp_line
			(start -0.7874 -0.4064)
			(end -0.7874 0.4064)
			(stroke
				(width 0.1524)
				(type default)
			)
			(layer "B.SilkS")
		)
		(fp_poly
			(pts
				(xy 0.508 0.2794) (xy 0.508 0.2286) (xy 0.635 0.2286) (xy 0.635 -0.254) (xy 0.5334 -0.254) (xy 0.5334 -0.2794)
				(xy -0.5334 -0.2794) (xy -0.5334 -0.254) (xy -0.635 -0.254) (xy -0.635 0.254) (xy -0.5334 0.254)
				(xy -0.5334 0.2794)
			)
			(stroke
				(width 0)
				(type default)
			)
			(fill no)
			(layer "B.CrtYd")
		)
		(pad "1" smd rect
			(at -0.40005 0)
			(size 0.4572 0.508)
			(layers "B.Cu" "B.Mask" "B.Paste")
			(net "H_CPU_NODE1_ERR1")
		)
		(pad "2" smd rect
			(at 0.40005 0)
			(size 0.4572 0.508)
			(layers "B.Cu" "B.Mask" "B.Paste")
			(net "H_CPU_NODE1_ERR1_R")
		)
	)
	(footprint ""
		(layer "B.Cu")
		(at 126.039626 -41.214294 180)
		(property "Reference" "R1138"
			(at -2.611374 3.513836 0)
			(unlocked yes)
			(layer "B.SilkS")
			(effects
				(font
					(size 0.7874 0.5842)
					(thickness 0.1524)
				)
				(justify left mirror)
			)
		)
		(property "Value" ""
			(at 0 0 0)
			(layer "B.Fab")
			(effects
				(font
					(size 1.27 1.27)
				)
				(justify mirror)
			)
		)
		(duplicate_pad_numbers_are_jumpers no)
		(fp_line
			(start 0.7874 0.4064)
			(end 0.7874 -0.4064)
			(stroke
				(width 0.1524)
				(type default)
			)
			(layer "B.SilkS")
		)
		(fp_line
			(start 0.7874 -0.4064)
			(end -0.7874 -0.4064)
			(stroke
				(width 0.1524)
				(type default)
			)
			(layer "B.SilkS")
		)
		(fp_line
			(start -0.7874 0.4064)
			(end 0.7874 0.4064)
			(stroke
				(width 0.1524)
				(type default)
			)
			(layer "B.SilkS")
		)
		(fp_line
			(start -0.7874 -0.4064)
			(end -0.7874 0.4064)
			(stroke
				(width 0.1524)
				(type default)
			)
			(layer "B.SilkS")
		)
		(fp_poly
			(pts
				(xy 0.508 0.2794) (xy 0.508 0.2286) (xy 0.635 0.2286) (xy 0.635 -0.254) (xy 0.5334 -0.254) (xy 0.5334 -0.2794)
				(xy -0.5334 -0.2794) (xy -0.5334 -0.254) (xy -0.635 -0.254) (xy -0.635 0.254) (xy -0.5334 0.254)
				(xy -0.5334 0.2794)
			)
			(stroke
				(width 0)
				(type default)
			)
			(fill no)
			(layer "B.CrtYd")
		)
		(pad "1" smd rect
			(at -0.40005 0)
			(size 0.4572 0.508)
			(layers "B.Cu" "B.Mask" "B.Paste")
			(net "P3V3_NODE1")
		)
		(pad "2" smd rect
			(at 0.40005 0)
			(size 0.4572 0.508)
			(layers "B.Cu" "B.Mask" "B.Paste")
			(net "SIO_PIN45")
		)
	)
	(footprint ""
		(layer "B.Cu")
		(at 41.697402 -159.164782 -90)
		(property "Reference" "C408"
			(at -7.088378 6.84276 270)
			(unlocked yes)
			(layer "B.SilkS")
			(effects
				(font
					(size 0.7874 0.5842)
					(thickness 0.1524)
				)
				(justify left mirror)
			)
		)
		(property "Value" ""
			(at 0 0 90)
			(layer "B.Fab")
			(effects
				(font
					(size 1.27 1.27)
				)
				(justify mirror)
			)
		)
		(duplicate_pad_numbers_are_jumpers no)
		(fp_line
			(start -0.7874 0.4064)
			(end 0.7874 0.4064)
			(stroke
				(width 0.1524)
				(type default)
			)
			(layer "B.SilkS")
		)
		(fp_line
			(start 0.7874 0.4064)
			(end 0.7874 -0.4064)
			(stroke
				(width 0.1524)
				(type default)
			)
			(layer "B.SilkS")
		)
		(fp_line
			(start 0 0.381)
			(end 0 -0.381)
			(stroke
				(width 0.1524)
				(type default)
			)
			(layer "B.SilkS")
		)
		(fp_line
			(start -0.7874 -0.4064)
			(end -0.7874 0.4064)
			(stroke
				(width 0.1524)
				(type default)
			)
			(layer "B.SilkS")
		)
		(fp_line
			(start 0.7874 -0.4064)
			(end -0.7874 -0.4064)
			(stroke
				(width 0.1524)
				(type default)
			)
			(layer "B.SilkS")
		)
		(fp_poly
			(pts
				(xy 0.5334 0.254) (xy 0.635 0.254) (xy 0.635 0.2286) (xy 0.635 -0.254) (xy 0.5334 -0.254) (xy 0.5334 -0.2794)
				(xy -0.5334 -0.2794) (xy -0.5334 -0.254) (xy -0.635 -0.254) (xy -0.635 0.254) (xy -0.5334 0.254)
				(xy -0.5334 0.2794) (xy 0.508 0.2794) (xy 0.5334 0.2794)
			)
			(stroke
				(width 0)
				(type default)
			)
			(fill no)
			(layer "B.CrtYd")
		)
		(pad "1" smd rect
			(at -0.40005 0 90)
			(size 0.4572 0.508)
			(layers "B.Cu" "B.Mask" "B.Paste")
			(net "P1V9_LAN1")
		)
		(pad "2" smd rect
			(at 0.40005 0 90)
			(size 0.4572 0.508)
			(layers "B.Cu" "B.Mask" "B.Paste")
			(net "GND")
		)
	)
	(footprint ""
		(layer "B.Cu")
		(at 64.899286 -121.044462 90)
		(property "Reference" "R337"
			(at -7.37235 10.060432 270)
			(unlocked yes)
			(layer "B.SilkS")
			(effects
				(font
					(size 0.7874 0.5842)
					(thickness 0.1524)
				)
				(justify left mirror)
			)
		)
		(property "Value" ""
			(at 0 0 90)
			(layer "B.Fab")
			(effects
				(font
					(size 1.27 1.27)
				)
				(justify mirror)
			)
		)
		(duplicate_pad_numbers_are_jumpers no)
		(fp_line
			(start 0.7874 -0.4064)
			(end -0.7874 -0.4064)
			(stroke
				(width 0.1524)
				(type default)
			)
			(layer "B.SilkS")
		)
		(fp_line
			(start -0.7874 -0.4064)
			(end -0.7874 0.4064)
			(stroke
				(width 0.1524)
				(type default)
			)
			(layer "B.SilkS")
		)
		(fp_line
			(start 0.7874 0.4064)
			(end 0.7874 -0.4064)
			(stroke
				(width 0.1524)
				(type default)
			)
			(layer "B.SilkS")
		)
		(fp_line
			(start -0.7874 0.4064)
			(end 0.7874 0.4064)
			(stroke
				(width 0.1524)
				(type default)
			)
			(layer "B.SilkS")
		)
		(fp_poly
			(pts
				(xy 0.508 0.2794) (xy 0.508 0.2286) (xy 0.635 0.2286) (xy 0.635 -0.254) (xy 0.5334 -0.254) (xy 0.5334 -0.2794)
				(xy -0.5334 -0.2794) (xy -0.5334 -0.254) (xy -0.635 -0.254) (xy -0.635 0.254) (xy -0.5334 0.254)
				(xy -0.5334 0.2794)
			)
			(stroke
				(width 0)
				(type default)
			)
			(fill no)
			(layer "B.CrtYd")
		)
		(pad "1" smd rect
			(at -0.40005 0 270)
			(size 0.4572 0.508)
			(layers "B.Cu" "B.Mask" "B.Paste")
			(net "P3V3_NODE1")
		)
		(pad "2" smd rect
			(at 0.40005 0 270)
			(size 0.4572 0.508)
			(layers "B.Cu" "B.Mask" "B.Paste")
			(net "BMC_ROMA21")
		)
	)
	(footprint ""
		(layer "B.Cu")
		(at 168.265856 -171.85513 180)
		(property "Reference" "C919"
			(at -4.778756 -0.232918 0)
			(unlocked yes)
			(layer "B.SilkS")
			(effects
				(font
					(size 0.7874 0.5842)
					(thickness 0.1524)
				)
				(justify left mirror)
			)
		)
		(property "Value" ""
			(at 0 0 0)
			(layer "B.Fab")
			(effects
				(font
					(size 1.27 1.27)
				)
				(justify mirror)
			)
		)
		(duplicate_pad_numbers_are_jumpers no)
		(fp_line
			(start 0.7874 0.4064)
			(end 0.7874 -0.4064)
			(stroke
				(width 0.1524)
				(type default)
			)
			(layer "B.SilkS")
		)
		(fp_line
			(start 0.7874 -0.4064)
			(end -0.7874 -0.4064)
			(stroke
				(width 0.1524)
				(type default)
			)
			(layer "B.SilkS")
		)
		(fp_line
			(start 0 0.381)
			(end 0 -0.381)
			(stroke
				(width 0.1524)
				(type default)
			)
			(layer "B.SilkS")
		)
		(fp_line
			(start -0.7874 0.4064)
			(end 0.7874 0.4064)
			(stroke
				(width 0.1524)
				(type default)
			)
			(layer "B.SilkS")
		)
		(fp_line
			(start -0.7874 -0.4064)
			(end -0.7874 0.4064)
			(stroke
				(width 0.1524)
				(type default)
			)
			(layer "B.SilkS")
		)
		(fp_poly
			(pts
				(xy 0.5334 0.254) (xy 0.635 0.254) (xy 0.635 0.2286) (xy 0.635 -0.254) (xy 0.5334 -0.254) (xy 0.5334 -0.2794)
				(xy -0.5334 -0.2794) (xy -0.5334 -0.254) (xy -0.635 -0.254) (xy -0.635 0.254) (xy -0.5334 0.254)
				(xy -0.5334 0.2794) (xy 0.508 0.2794) (xy 0.5334 0.2794)
			)
			(stroke
				(width 0)
				(type default)
			)
			(fill no)
			(layer "B.CrtYd")
		)
		(pad "1" smd rect
			(at -0.40005 0)
			(size 0.4572 0.508)
			(layers "B.Cu" "B.Mask" "B.Paste")
			(net "GND")
		)
		(pad "2" smd rect
			(at 0.40005 0)
			(size 0.4572 0.508)
			(layers "B.Cu" "B.Mask" "B.Paste")
			(net "N54365835")
		)
	)
	(footprint ""
		(layer "B.Cu")
		(at 63.215266 -76.034392)
		(property "Reference" "C47"
			(at -13.728446 30.440884 0)
			(unlocked yes)
			(layer "B.SilkS")
			(effects
				(font
					(size 0.7874 0.5842)
					(thickness 0.1524)
				)
				(justify left mirror)
			)
		)
		(property "Value" ""
			(at 0 0 0)
			(layer "B.Fab")
			(effects
				(font
					(size 1.27 1.27)
				)
				(justify mirror)
			)
		)
		(duplicate_pad_numbers_are_jumpers no)
		(fp_line
			(start -0.7874 -0.4064)
			(end -0.7874 0.4064)
			(stroke
				(width 0.1524)
				(type default)
			)
			(layer "B.SilkS")
		)
		(fp_line
			(start -0.7874 0.4064)
			(end 0.7874 0.4064)
			(stroke
				(width 0.1524)
				(type default)
			)
			(layer "B.SilkS")
		)
		(fp_line
			(start 0 0.381)
			(end 0 -0.381)
			(stroke
				(width 0.1524)
				(type default)
			)
			(layer "B.SilkS")
		)
		(fp_line
			(start 0.7874 -0.4064)
			(end -0.7874 -0.4064)
			(stroke
				(width 0.1524)
				(type default)
			)
			(layer "B.SilkS")
		)
		(fp_line
			(start 0.7874 0.4064)
			(end 0.7874 -0.4064)
			(stroke
				(width 0.1524)
				(type default)
			)
			(layer "B.SilkS")
		)
		(fp_poly
			(pts
				(xy 0.5334 0.254) (xy 0.635 0.254) (xy 0.635 0.2286) (xy 0.635 -0.254) (xy 0.5334 -0.254) (xy 0.5334 -0.2794)
				(xy -0.5334 -0.2794) (xy -0.5334 -0.254) (xy -0.635 -0.254) (xy -0.635 0.254) (xy -0.5334 0.254)
				(xy -0.5334 0.2794) (xy 0.508 0.2794) (xy 0.5334 0.2794)
			)
			(stroke
				(width 0)
				(type default)
			)
			(fill no)
			(layer "B.CrtYd")
		)
		(pad "1" smd rect
			(at -0.40005 0 180)
			(size 0.4572 0.508)
			(layers "B.Cu" "B.Mask" "B.Paste")
			(net "P1V05_NODE1")
		)
		(pad "2" smd rect
			(at 0.40005 0 180)
			(size 0.4572 0.508)
			(layers "B.Cu" "B.Mask" "B.Paste")
			(net "GND")
		)
	)
)
